(kicad_pcb
	(version 20221018)
	(generator pcbnew)
	(general
    (thickness 1.62)
  )
	(paper "A4")
	(title_block
    (title "ECP5 - Datacenter Secure Control Module (DC-SCM)")
    (date "2024-07-01")
    (rev "1.2.1")
		(comment 9 "footprints 255-263 of 506")
	)
	(layers
    (0 "F.Cu" signal)
    (1 "In1.Cu" power)
    (2 "In2.Cu" signal)
    (3 "In3.Cu" power)
    (4 "In4.Cu" power)
    (5 "In5.Cu" signal)
    (6 "In6.Cu" power)
    (31 "B.Cu" signal)
    (32 "B.Adhes" user "B.Adhesive")
    (33 "F.Adhes" user "F.Adhesive")
    (34 "B.Paste" user)
    (35 "F.Paste" user)
    (36 "B.SilkS" user "B.Silkscreen")
    (37 "F.SilkS" user "F.Silkscreen")
    (38 "B.Mask" user)
    (39 "F.Mask" user)
    (40 "Dwgs.User" user "User.Drawings")
    (41 "Cmts.User" user "User.Comments")
    (42 "Eco1.User" user "User.Eco1")
    (43 "Eco2.User" user "User.Eco2")
    (44 "Edge.Cuts" user)
    (45 "Margin" user)
    (46 "B.CrtYd" user "B.Courtyard")
    (47 "F.CrtYd" user "F.Courtyard")
    (48 "B.Fab" user)
    (49 "F.Fab" user)
  )
	(footprint "antmicro-footprints:C_0402_1005Metric" (layer "B.Cu")
    (at 84.8 121.4 -90)
    (descr "Capacitor SMD 0402")
    (tags "capacitor SMD 0402")
    (property "Author" "Antmicro")
    (property "Dielectric" "")
    (property "License" "Apache-2.0")
    (property "MPN" "C1005X5R1E474M050BB")
    (property "Manufacturer" "TDK")
    (property "Public" "False")
    (property "Sheetfile" "ddr3.kicad_sch")
    (property "Sheetname" "DDR3")
    (property "Val" "470n")
    (property "Voltage" "")
    (property "ki_description" "SMD Multilayer Ceramic Capacitor, 0.47 µF, 25 V, 0402 [1005 Metric], ± 20%, X5R, C")
    (property "ki_keywords" "0402, SMT, CAPACITOR, PASSIVE, CERAMIC, MLCC")
    (attr smd)
    (fp_text reference "C85" (at -1.225 -0.53 -180) (layer "B.SilkS")
        (effects (font (size 0.7 0.7) (thickness 0.127)) (justify mirror))
    )
    (fp_text value "C_470n_0402" (at 0 -1.17 90) (layer "B.Fab")
        (effects (font (size 1 1) (thickness 0.15)) (justify mirror))
    )
    (fp_text user "Author: Antmicro" (at -0.939 -3.399 90) (layer "B.Fab") hide
        (effects (font (size 0.7 0.7) (thickness 0.15)) (justify left bottom mirror))
    )
    (fp_text user "License: Apache-2.0" (at -0.939 -5.799 90) (layer "B.Fab") hide
        (effects (font (size 0.7 0.7) (thickness 0.15)) (justify left bottom mirror))
    )
    (fp_text user "${REFERENCE}" (at 0 0 90) (layer "B.Fab")
        (effects (font (size 0.25 0.25) (thickness 0.04)) (justify mirror))
    )
    (fp_rect (start -0.925 0.47) (end 0.925 -0.47)
      (stroke (width 0.05) (type default)) (fill none) (layer "B.CrtYd"))
    (fp_line (start -0.494 -0.248) (end -0.494 0.25)
      (stroke (width 0.15) (type solid)) (layer "B.Fab"))
    (fp_line (start -0.494 0.25) (end 0.504 0.25)
      (stroke (width 0.15) (type solid)) (layer "B.Fab"))
    (fp_line (start 0.504 -0.248) (end -0.494 -0.248)
      (stroke (width 0.15) (type solid)) (layer "B.Fab"))
    (fp_line (start 0.504 0.25) (end 0.504 -0.248)
      (stroke (width 0.15) (type solid)) (layer "B.Fab"))
    (pad "1" smd roundrect (at -0.48 0 270) (size 0.59 0.64) (layers "B.Cu" "B.Paste" "B.Mask") (roundrect_rratio 0.25)
      (net 1 "GND") (pintype "passive"))
    (pad "2" smd roundrect (at 0.48 0 270) (size 0.59 0.64) (layers "B.Cu" "B.Paste" "B.Mask") (roundrect_rratio 0.25)
      (net 3 "VCC1V35") (pintype "passive"))
  )
	(footprint "antmicro-footprints:C_0402_1005Metric" (layer "B.Cu")
    (at 85.9 127.25 180)
    (descr "Capacitor SMD 0402")
    (tags "capacitor SMD 0402")
    (property "Author" "Antmicro")
    (property "Dielectric" "")
    (property "License" "Apache-2.0")
    (property "MPN" "C1005X5R1E474M050BB")
    (property "Manufacturer" "TDK")
    (property "Public" "False")
    (property "Sheetfile" "ddr3.kicad_sch")
    (property "Sheetname" "DDR3")
    (property "Val" "470n")
    (property "Voltage" "")
    (property "ki_description" "SMD Multilayer Ceramic Capacitor, 0.47 µF, 25 V, 0402 [1005 Metric], ± 20%, X5R, C")
    (property "ki_keywords" "0402, SMT, CAPACITOR, PASSIVE, CERAMIC, MLCC")
    (attr smd)
    (fp_text reference "C86" (at 1.89 0.045) (layer "B.SilkS")
        (effects (font (size 0.7 0.7) (thickness 0.127)) (justify mirror))
    )
    (fp_text value "C_470n_0402" (at 0 -1.17) (layer "B.Fab")
        (effects (font (size 1 1) (thickness 0.15)) (justify mirror))
    )
    (fp_text user "License: Apache-2.0" (at -0.939 -5.799) (layer "B.Fab") hide
        (effects (font (size 0.7 0.7) (thickness 0.15)) (justify left bottom mirror))
    )
    (fp_text user "${REFERENCE}" (at 0 0) (layer "B.Fab")
        (effects (font (size 0.25 0.25) (thickness 0.04)) (justify mirror))
    )
    (fp_text user "Author: Antmicro" (at -0.939 -3.399) (layer "B.Fab") hide
        (effects (font (size 0.7 0.7) (thickness 0.15)) (justify left bottom mirror))
    )
    (fp_rect (start -0.925 0.47) (end 0.925 -0.47)
      (stroke (width 0.05) (type default)) (fill none) (layer "B.CrtYd"))
    (fp_line (start -0.494 -0.248) (end -0.494 0.25)
      (stroke (width 0.15) (type solid)) (layer "B.Fab"))
    (fp_line (start -0.494 0.25) (end 0.504 0.25)
      (stroke (width 0.15) (type solid)) (layer "B.Fab"))
    (fp_line (start 0.504 -0.248) (end -0.494 -0.248)
      (stroke (width 0.15) (type solid)) (layer "B.Fab"))
    (fp_line (start 0.504 0.25) (end 0.504 -0.248)
      (stroke (width 0.15) (type solid)) (layer "B.Fab"))
    (pad "1" smd roundrect (at -0.48 0 180) (size 0.59 0.64) (layers "B.Cu" "B.Paste" "B.Mask") (roundrect_rratio 0.25)
      (net 1 "GND") (pintype "passive"))
    (pad "2" smd roundrect (at 0.48 0 180) (size 0.59 0.64) (layers "B.Cu" "B.Paste" "B.Mask") (roundrect_rratio 0.25)
      (net 3 "VCC1V35") (pintype "passive"))
  )
	(footprint "antmicro-footprints:C_0402_1005Metric" (layer "B.Cu")
    (at 87.75 121.6 -90)
    (descr "Capacitor SMD 0402")
    (tags "capacitor SMD 0402")
    (property "Author" "Antmicro")
    (property "Dielectric" "X5R")
    (property "License" "Apache-2.0")
    (property "MPN" "GRM155R61H104KE14D")
    (property "Manufacturer" "Murata")
    (property "Public" "False")
    (property "Sheetfile" "ddr3.kicad_sch")
    (property "Sheetname" "DDR3")
    (property "Val" "100n")
    (property "Voltage" "50V")
    (property "ki_description" "SMD Multilayer Ceramic Capacitor, 0.1 µF, 50 V, 0402 [1005 Metric], ± 10%, X5R, GRM Series")
    (property "ki_keywords" "0402, SMT, CAPACITOR, PASSIVE, CERAMIC, MLCC")
    (attr smd)
    (fp_text reference "C88" (at -0.025 0.99 90) (layer "B.SilkS")
        (effects (font (size 0.7 0.7) (thickness 0.127)) (justify mirror))
    )
    (fp_text value "C_100n_0402" (at 0 -1.17 90) (layer "B.Fab")
        (effects (font (size 1 1) (thickness 0.15)) (justify mirror))
    )
    (fp_text user "Author: Antmicro" (at -0.939 -3.399 90) (layer "B.Fab") hide
        (effects (font (size 0.7 0.7) (thickness 0.15)) (justify left bottom mirror))
    )
    (fp_text user "License: Apache-2.0" (at -0.939 -5.799 90) (layer "B.Fab") hide
        (effects (font (size 0.7 0.7) (thickness 0.15)) (justify left bottom mirror))
    )
    (fp_text user "${REFERENCE}" (at 0 0 90) (layer "B.Fab")
        (effects (font (size 0.25 0.25) (thickness 0.04)) (justify mirror))
    )
    (fp_rect (start -0.925 0.47) (end 0.925 -0.47)
      (stroke (width 0.05) (type default)) (fill none) (layer "B.CrtYd"))
    (fp_line (start -0.494 -0.248) (end -0.494 0.25)
      (stroke (width 0.15) (type solid)) (layer "B.Fab"))
    (fp_line (start -0.494 0.25) (end 0.504 0.25)
      (stroke (width 0.15) (type solid)) (layer "B.Fab"))
    (fp_line (start 0.504 -0.248) (end -0.494 -0.248)
      (stroke (width 0.15) (type solid)) (layer "B.Fab"))
    (fp_line (start 0.504 0.25) (end 0.504 -0.248)
      (stroke (width 0.15) (type solid)) (layer "B.Fab"))
    (pad "1" smd roundrect (at -0.48 0 270) (size 0.59 0.64) (layers "B.Cu" "B.Paste" "B.Mask") (roundrect_rratio 0.25)
      (net 1 "GND") (pintype "passive"))
    (pad "2" smd roundrect (at 0.48 0 270) (size 0.59 0.64) (layers "B.Cu" "B.Paste" "B.Mask") (roundrect_rratio 0.25)
      (net 217 "DDR3_VREF") (pintype "passive"))
  )
	(footprint "antmicro-footprints:C_0402_1005Metric" (layer "B.Cu")
    (at 88.45 119.395 180)
    (descr "Capacitor SMD 0402")
    (tags "capacitor SMD 0402")
    (property "Author" "Antmicro")
    (property "Dielectric" "")
    (property "License" "Apache-2.0")
    (property "MPN" "C1005X5R1E474M050BB")
    (property "Manufacturer" "TDK")
    (property "Public" "False")
    (property "Sheetfile" "ddr3.kicad_sch")
    (property "Sheetname" "DDR3")
    (property "Val" "470n")
    (property "Voltage" "")
    (property "ki_description" "SMD Multilayer Ceramic Capacitor, 0.47 µF, 25 V, 0402 [1005 Metric], ± 20%, X5R, C")
    (property "ki_keywords" "0402, SMT, CAPACITOR, PASSIVE, CERAMIC, MLCC")
    (attr smd)
    (fp_text reference "C89" (at -1.89 0.025) (layer "B.SilkS")
        (effects (font (size 0.7 0.7) (thickness 0.127)) (justify mirror))
    )
    (fp_text value "C_470n_0402" (at 0 -1.17) (layer "B.Fab")
        (effects (font (size 1 1) (thickness 0.15)) (justify mirror))
    )
    (fp_text user "Author: Antmicro" (at -0.939 -3.399) (layer "B.Fab") hide
        (effects (font (size 0.7 0.7) (thickness 0.15)) (justify left bottom mirror))
    )
    (fp_text user "License: Apache-2.0" (at -0.939 -5.799) (layer "B.Fab") hide
        (effects (font (size 0.7 0.7) (thickness 0.15)) (justify left bottom mirror))
    )
    (fp_text user "${REFERENCE}" (at 0 0) (layer "B.Fab")
        (effects (font (size 0.25 0.25) (thickness 0.04)) (justify mirror))
    )
    (fp_rect (start -0.925 0.47) (end 0.925 -0.47)
      (stroke (width 0.05) (type default)) (fill none) (layer "B.CrtYd"))
    (fp_line (start -0.494 -0.248) (end -0.494 0.25)
      (stroke (width 0.15) (type solid)) (layer "B.Fab"))
    (fp_line (start -0.494 0.25) (end 0.504 0.25)
      (stroke (width 0.15) (type solid)) (layer "B.Fab"))
    (fp_line (start 0.504 -0.248) (end -0.494 -0.248)
      (stroke (width 0.15) (type solid)) (layer "B.Fab"))
    (fp_line (start 0.504 0.25) (end 0.504 -0.248)
      (stroke (width 0.15) (type solid)) (layer "B.Fab"))
    (pad "1" smd roundrect (at -0.48 0 180) (size 0.59 0.64) (layers "B.Cu" "B.Paste" "B.Mask") (roundrect_rratio 0.25)
      (net 1 "GND") (pintype "passive"))
    (pad "2" smd roundrect (at 0.48 0 180) (size 0.59 0.64) (layers "B.Cu" "B.Paste" "B.Mask") (roundrect_rratio 0.25)
      (net 3 "VCC1V35") (pintype "passive"))
  )
	(footprint "antmicro-footprints:C_0402_1005Metric" (layer "B.Cu")
    (at 80.29 130.545)
    (descr "Capacitor SMD 0402")
    (tags "capacitor SMD 0402")
    (property "Author" "Antmicro")
    (property "Dielectric" "")
    (property "License" "Apache-2.0")
    (property "MPN" "C1005X5R1E474M050BB")
    (property "Manufacturer" "TDK")
    (property "Public" "False")
    (property "Sheetfile" "ddr3.kicad_sch")
    (property "Sheetname" "DDR3")
    (property "Val" "470n")
    (property "Voltage" "")
    (property "ki_description" "SMD Multilayer Ceramic Capacitor, 0.47 µF, 25 V, 0402 [1005 Metric], ± 20%, X5R, C")
    (property "ki_keywords" "0402, SMT, CAPACITOR, PASSIVE, CERAMIC, MLCC")
    (attr smd)
    (fp_text reference "C92" (at -0.01 0.9) (layer "B.SilkS")
        (effects (font (size 0.7 0.7) (thickness 0.127)) (justify mirror))
    )
    (fp_text value "C_470n_0402" (at 0 -1.17) (layer "B.Fab")
        (effects (font (size 1 1) (thickness 0.15)) (justify mirror))
    )
    (fp_text user "License: Apache-2.0" (at -0.939 -5.799 180) (layer "B.Fab") hide
        (effects (font (size 0.7 0.7) (thickness 0.15)) (justify left bottom mirror))
    )
    (fp_text user "Author: Antmicro" (at -0.939 -3.399 180) (layer "B.Fab") hide
        (effects (font (size 0.7 0.7) (thickness 0.15)) (justify left bottom mirror))
    )
    (fp_text user "${REFERENCE}" (at 0 0) (layer "B.Fab")
        (effects (font (size 0.25 0.25) (thickness 0.04)) (justify mirror))
    )
    (fp_rect (start -0.925 0.47) (end 0.925 -0.47)
      (stroke (width 0.05) (type default)) (fill none) (layer "B.CrtYd"))
    (fp_line (start -0.494 -0.248) (end -0.494 0.25)
      (stroke (width 0.15) (type solid)) (layer "B.Fab"))
    (fp_line (start -0.494 0.25) (end 0.504 0.25)
      (stroke (width 0.15) (type solid)) (layer "B.Fab"))
    (fp_line (start 0.504 -0.248) (end -0.494 -0.248)
      (stroke (width 0.15) (type solid)) (layer "B.Fab"))
    (fp_line (start 0.504 0.25) (end 0.504 -0.248)
      (stroke (width 0.15) (type solid)) (layer "B.Fab"))
    (pad "1" smd roundrect (at -0.48 0) (size 0.59 0.64) (layers "B.Cu" "B.Paste" "B.Mask") (roundrect_rratio 0.25)
      (net 1 "GND") (pintype "passive"))
    (pad "2" smd roundrect (at 0.48 0) (size 0.59 0.64) (layers "B.Cu" "B.Paste" "B.Mask") (roundrect_rratio 0.25)
      (net 3 "VCC1V35") (pintype "passive"))
  )
	(footprint "antmicro-footprints:C_0402_1005Metric" (layer "B.Cu")
    (at 80.64 125.095 -90)
    (descr "Capacitor SMD 0402")
    (tags "capacitor SMD 0402")
    (property "Author" "Antmicro")
    (property "Dielectric" "X5R")
    (property "License" "Apache-2.0")
    (property "MPN" "GRM155R61H104KE14D")
    (property "Manufacturer" "Murata")
    (property "Public" "False")
    (property "Sheetfile" "ddr3.kicad_sch")
    (property "Sheetname" "DDR3")
    (property "Val" "100n")
    (property "Voltage" "50V")
    (property "ki_description" "SMD Multilayer Ceramic Capacitor, 0.1 µF, 50 V, 0402 [1005 Metric], ± 10%, X5R, GRM Series")
    (property "ki_keywords" "0402, SMT, CAPACITOR, PASSIVE, CERAMIC, MLCC")
    (attr smd)
    (fp_text reference "C94" (at 2.58 4.64 90) (layer "B.SilkS")
        (effects (font (size 0.7 0.7) (thickness 0.127)) (justify mirror))
    )
    (fp_text value "C_100n_0402" (at 0 -1.17 90) (layer "B.Fab")
        (effects (font (size 1 1) (thickness 0.15)) (justify mirror))
    )
    (fp_text user "${REFERENCE}" (at 0 0 90) (layer "B.Fab")
        (effects (font (size 0.25 0.25) (thickness 0.04)) (justify mirror))
    )
    (fp_text user "Author: Antmicro" (at -0.939 -3.399 90) (layer "B.Fab") hide
        (effects (font (size 0.7 0.7) (thickness 0.15)) (justify left bottom mirror))
    )
    (fp_text user "License: Apache-2.0" (at -0.939 -5.799 90) (layer "B.Fab") hide
        (effects (font (size 0.7 0.7) (thickness 0.15)) (justify left bottom mirror))
    )
    (fp_rect (start -0.925 0.47) (end 0.925 -0.47)
      (stroke (width 0.05) (type default)) (fill none) (layer "B.CrtYd"))
    (fp_line (start -0.494 -0.248) (end -0.494 0.25)
      (stroke (width 0.15) (type solid)) (layer "B.Fab"))
    (fp_line (start -0.494 0.25) (end 0.504 0.25)
      (stroke (width 0.15) (type solid)) (layer "B.Fab"))
    (fp_line (start 0.504 -0.248) (end -0.494 -0.248)
      (stroke (width 0.15) (type solid)) (layer "B.Fab"))
    (fp_line (start 0.504 0.25) (end 0.504 -0.248)
      (stroke (width 0.15) (type solid)) (layer "B.Fab"))
    (pad "1" smd roundrect (at -0.48 0 270) (size 0.59 0.64) (layers "B.Cu" "B.Paste" "B.Mask") (roundrect_rratio 0.25)
      (net 228 "Net-(C94-Pad1)") (pintype "passive"))
    (pad "2" smd roundrect (at 0.48 0 270) (size 0.59 0.64) (layers "B.Cu" "B.Paste" "B.Mask") (roundrect_rratio 0.25)
      (net 1 "GND") (pintype "passive"))
  )
	(footprint "antmicro-footprints:R_0402_1005Metric" (layer "B.Cu")
    (at 125.225 111.425 180)
    (descr "Resistor SMD 0402")
    (tags "resistor SMD 0402")
    (property "Author" "Antmicro")
    (property "License" "Apache-2.0")
    (property "MPN" "CR0402-FX-1001GLF")
    (property "Manufacturer" "Bourns")
    (property "Public" "False")
    (property "Sheetfile" "interfaces.kicad_sch")
    (property "Sheetname" "Interfaces")
    (property "Tolerance" "1%")
    (property "Val" "1k")
    (property "ki_description" "SMD Chip Resistor, 1 kohm, ± 1%, 63 mW, 0402 [1005 Metric], Thick Film, General Purpose")
    (property "ki_keywords" "0402, SMT, RESISTOR, PASSIVE")
    (attr smd)
    (fp_text reference "R76" (at 0.025 1.025) (layer "B.SilkS")
        (effects (font (size 0.7 0.7) (thickness 0.127)) (justify mirror))
    )
    (fp_text value "R_1k_0402" (at 0 -1.17) (layer "B.Fab")
        (effects (font (size 1 1) (thickness 0.15)) (justify mirror))
    )
    (fp_text user "${REFERENCE}" (at 0 0) (layer "B.Fab")
        (effects (font (size 0.25 0.25) (thickness 0.04)) (justify mirror))
    )
    (fp_text user "Author: Antmicro" (at -0.95 -4.169) (layer "B.Fab") hide
        (effects (font (size 0.7 0.7) (thickness 0.15)) (justify left bottom mirror))
    )
    (fp_text user "License: Apache-2.0" (at -0.95 -5.169) (layer "B.Fab") hide
        (effects (font (size 0.7 0.7) (thickness 0.15)) (justify left bottom mirror))
    )
    (fp_rect (start -0.925 0.47) (end 0.925 -0.47)
      (stroke (width 0.05) (type default)) (fill none) (layer "B.CrtYd"))
    (fp_rect (start -0.5 0.25) (end 0.5 -0.25)
      (stroke (width 0.15) (type solid)) (fill none) (layer "B.Fab"))
    (pad "1" smd roundrect (at -0.48 0 180) (size 0.59 0.64) (layers "B.Cu" "B.Paste" "B.Mask") (roundrect_rratio 0.25)
      (net 11 "VCC5V0") (pintype "passive"))
    (pad "2" smd roundrect (at 0.48 0 180) (size 0.59 0.64) (layers "B.Cu" "B.Paste" "B.Mask") (roundrect_rratio 0.25)
      (net 406 "Net-(U9-VBUS)") (pintype "passive"))
  )
	(footprint "antmicro-footprints:R_0402_1005Metric" (layer "B.Cu")
    (at 78.615 123.195 180)
    (descr "Resistor SMD 0402")
    (tags "resistor SMD 0402")
    (property "Author" "Antmicro")
    (property "License" "Apache-2.0")
    (property "MPN" "CR0402-FX-2400GLF")
    (property "Manufacturer" "Bourns")
    (property "Public" "False")
    (property "Sheetfile" "ddr3.kicad_sch")
    (property "Sheetname" "DDR3")
    (property "Tolerance" "1%")
    (property "Val" "240R")
    (property "ki_description" "SMD Chip Resistor, 240 ohm, ± 1%, 63 mW, 0402 [1005 Metric], Thick Film, General Purpose")
    (property "ki_keywords" "0402, SMT, RESISTOR, PASSIVE")
    (attr smd)
    (fp_text reference "R81" (at 2.365 0.11) (layer "B.SilkS")
        (effects (font (size 0.7 0.7) (thickness 0.127)) (justify mirror))
    )
    (fp_text value "R_240R_0402" (at 0 -1.17) (layer "B.Fab")
        (effects (font (size 1 1) (thickness 0.15)) (justify mirror))
    )
    (fp_text user "Author: Antmicro" (at -0.95 -4.169) (layer "B.Fab") hide
        (effects (font (size 0.7 0.7) (thickness 0.15)) (justify left bottom mirror))
    )
    (fp_text user "License: Apache-2.0" (at -0.95 -5.169) (layer "B.Fab") hide
        (effects (font (size 0.7 0.7) (thickness 0.15)) (justify left bottom mirror))
    )
    (fp_text user "${REFERENCE}" (at 0 0) (layer "B.Fab")
        (effects (font (size 0.25 0.25) (thickness 0.04)) (justify mirror))
    )
    (fp_rect (start -0.925 0.47) (end 0.925 -0.47)
      (stroke (width 0.05) (type default)) (fill none) (layer "B.CrtYd"))
    (fp_rect (start -0.5 0.25) (end 0.5 -0.25)
      (stroke (width 0.15) (type solid)) (fill none) (layer "B.Fab"))
    (pad "1" smd roundrect (at -0.48 0 180) (size 0.59 0.64) (layers "B.Cu" "B.Paste" "B.Mask") (roundrect_rratio 0.25)
      (net 418 "Net-(U10-ZQ)") (pintype "passive"))
    (pad "2" smd roundrect (at 0.48 0 180) (size 0.59 0.64) (layers "B.Cu" "B.Paste" "B.Mask") (roundrect_rratio 0.25)
      (net 1 "GND") (pintype "passive"))
  )
	(footprint "antmicro-footprints:R_0402_1005Metric" (layer "B.Cu")
    (at 81.09 123.595 180)
    (descr "Resistor SMD 0402")
    (tags "resistor SMD 0402")
    (property "Author" "Antmicro")
    (property "License" "Apache-2.0")
    (property "MPN" "CR0402-FX-51R0GLF")
    (property "Manufacturer" "Bourns")
    (property "Public" "False")
    (property "Sheetfile" "ddr3.kicad_sch")
    (property "Sheetname" "DDR3")
    (property "Tolerance" "1%")
    (property "Val" "51R")
    (property "ki_description" "SMD Chip Resistor, 51 ohm, ± 1%, 63 mW, 0402 [1005 Metric], Thick Film, General Purpose")
    (property "ki_keywords" "0402, SMT, RESISTOR, PASSIVE")
    (attr smd)
    (fp_text reference "R82" (at 0.01 -3.79) (layer "B.SilkS")
        (effects (font (size 0.7 0.7) (thickness 0.127)) (justify mirror))
    )
    (fp_text value "R_51R_0402" (at 0 -1.17) (layer "B.Fab")
        (effects (font (size 1 1) (thickness 0.15)) (justify mirror))
    )
    (fp_text user "${REFERENCE}" (at 0 0) (layer "B.Fab")
        (effects (font (size 0.25 0.25) (thickness 0.04)) (justify mirror))
    )
    (fp_text user "License: Apache-2.0" (at -0.95 -5.169) (layer "B.Fab") hide
        (effects (font (size 0.7 0.7) (thickness 0.15)) (justify left bottom mirror))
    )
    (fp_text user "Author: Antmicro" (at -0.95 -4.169) (layer "B.Fab") hide
        (effects (font (size 0.7 0.7) (thickness 0.15)) (justify left bottom mirror))
    )
    (fp_rect (start -0.925 0.47) (end 0.925 -0.47)
      (stroke (width 0.05) (type default)) (fill none) (layer "B.CrtYd"))
    (fp_rect (start -0.5 0.25) (end 0.5 -0.25)
      (stroke (width 0.15) (type solid)) (fill none) (layer "B.Fab"))
    (pad "1" smd roundrect (at -0.48 0 180) (size 0.59 0.64) (layers "B.Cu" "B.Paste" "B.Mask") (roundrect_rratio 0.25)
      (net 261 "DDR3_CLK+") (pintype "passive"))
    (pad "2" smd roundrect (at 0.48 0 180) (size 0.59 0.64) (layers "B.Cu" "B.Paste" "B.Mask") (roundrect_rratio 0.25)
      (net 228 "Net-(C94-Pad1)") (pintype "passive"))
  )
)
